(kicad_pcb
	(version 20260206)
	(generator "pcbnew")
	(generator_version "10.0")
	(general
		(thickness 1.6)
		(legacy_teardrops no)
	)
	(paper "A4")
	(title_block
		(title "Bryce Canyon_IOM_M2_16342-2_OCP.brd")
		(comment 1 "Bryce Canyon / footprints 412-420 of 1146")
	)
	(layers
		(0 "F.Cu" signal "TOP")
		(4 "In1.Cu" signal "L2GND")
		(6 "In2.Cu" signal "L3")
		(8 "In3.Cu" signal "L4VCC")
		(10 "In4.Cu" signal "L5VCC")
		(12 "In5.Cu" signal "L6")
		(14 "In6.Cu" signal "L7GND")
		(2 "B.Cu" signal "BOTTOM")
		(9 "F.Adhes" user "F.Adhesive")
		(11 "B.Adhes" user "B.Adhesive")
		(13 "F.Paste" user "Package Geometry/Pastemask Top")
		(15 "B.Paste" user "Package Geometry/Pastemask Bottom")
		(5 "F.SilkS" user "Ref Des/Silkscreen Top")
		(7 "B.SilkS" user "Ref Des/Silkscreen Bottom")
		(1 "F.Mask" user "Board Geometry/Soldermask Top")
		(3 "B.Mask" user "Board Geometry/Soldermask Bottom")
		(17 "Dwgs.User" user "User.Drawings")
		(19 "Cmts.User" user "User.Comments")
		(21 "Eco1.User" user "User.Eco1")
		(23 "Eco2.User" user "User.Eco2")
		(25 "Edge.Cuts" user "Board Geometry/Outline")
		(27 "Margin" user)
		(31 "F.CrtYd" user "Package Geometry/Place Bound Top")
		(29 "B.CrtYd" user "Package Geometry/Place Bound Bottom")
		(35 "F.Fab" user "Ref Des/Assembly Top")
		(33 "B.Fab" user "Ref Des/Assembly Bottom")
	)
	(footprint ""
		(layer "F.Cu")
		(at 43.3324 -161.417 180)
		(property "Reference" "R188"
			(at 0 0 180)
			(layer "F.SilkS")
			(hide yes)
			(effects
				(font
					(size 1.27 1.27)
				)
			)
		)
		(property "Value" "2K2R2F-GP"
			(at 0.064008 -3.993896 180)
			(unlocked yes)
			(layer "F.Fab")
			(hide yes)
			(effects
				(font
					(size 1.016 1.016)
					(thickness 0.1524)
				)
			)
		)
		(property "Device Type" "R402H16"
			(at 0.064008 -5.517896 180)
			(unlocked yes)
			(layer "F.Fab")
			(hide yes)
			(effects
				(font
					(size 1.016 1.016)
					(thickness 0.1524)
				)
			)
		)
		(duplicate_pad_numbers_are_jumpers no)
		(fp_line
			(start 0.508 -0.9398)
			(end -0.508 -0.9398)
			(stroke
				(width 0.1524)
				(type default)
			)
			(layer "F.SilkS")
		)
		(fp_line
			(start -0.508 -0.9398)
			(end -0.508 0.9398)
			(stroke
				(width 0.1524)
				(type default)
			)
			(layer "F.SilkS")
		)
		(fp_rect
			(start -0.508 0.9398)
			(end 0.508 -0.9398)
			(stroke
				(width 0)
				(type default)
			)
			(fill no)
			(layer "F.CrtYd")
		)
		(fp_rect
			(start -0.508 0.9398)
			(end 0.508 -0.9398)
			(stroke
				(width 0)
				(type default)
			)
			(fill no)
			(layer "F.Fab")
		)
		(pad "1" smd custom
			(at 0 -0.4445 180)
			(size 0.1397 0.1397)
			(layers "F.Cu" "F.Mask" "F.Paste")
			(net "I2C_M2_1_SDA")
			(options
				(clearance outline)
				(anchor circle)
			)
			(primitives
				(gr_poly
					(pts
						(arc
							(start -0.1778 -0.2794)
							(mid -0.249642 -0.249642)
							(end -0.2794 -0.1778)
						)
						(arc
							(start -0.2794 0.1778)
							(mid -0.249642 0.249642)
							(end -0.1778 0.2794)
						)
						(arc
							(start 0.1778 0.2794)
							(mid 0.249642 0.249642)
							(end 0.2794 0.1778)
						)
						(arc
							(start 0.2794 -0.1778)
							(mid 0.249642 -0.249642)
							(end 0.1778 -0.2794)
						)
					)
					(width 0)
					(fill yes)
				)
			)
		)
		(pad "2" smd custom
			(at 0 0.4445 180)
			(size 0.1397 0.1397)
			(layers "F.Cu" "F.Mask" "F.Paste")
			(net "P3V3_STBY")
			(options
				(clearance outline)
				(anchor circle)
			)
			(primitives
				(gr_poly
					(pts
						(arc
							(start -0.1778 -0.2794)
							(mid -0.249642 -0.249642)
							(end -0.2794 -0.1778)
						)
						(arc
							(start -0.2794 0.1778)
							(mid -0.249642 0.249642)
							(end -0.1778 0.2794)
						)
						(arc
							(start 0.1778 0.2794)
							(mid 0.249642 0.249642)
							(end 0.2794 0.1778)
						)
						(arc
							(start 0.2794 -0.1778)
							(mid 0.249642 -0.249642)
							(end 0.1778 -0.2794)
						)
					)
					(width 0)
					(fill yes)
				)
			)
		)
	)
	(footprint ""
		(layer "F.Cu")
		(at 222.499936 -153.999946)
		(property "Reference" ""
			(at 0 0 0)
			(layer "F.SilkS")
			(hide yes)
			(effects
				(font
					(size 1.27 1.27)
				)
			)
		)
		(property "Value" "*"
			(at -6.38175 0.19685 0)
			(unlocked yes)
			(layer "F.Fab")
			(hide yes)
			(effects
				(font
					(size 1.016 1.016)
					(thickness 0.1524)
				)
			)
		)
		(duplicate_pad_numbers_are_jumpers no)
		(fp_poly
			(pts
				(arc
					(start 5.0673 0)
					(mid -5.0673 0)
					(end 5.0673 0)
				)
			)
			(stroke
				(width 0)
				(type default)
			)
			(fill no)
			(layer "B.CrtYd")
		)
		(fp_poly
			(pts
				(arc
					(start 5.0673 0)
					(mid -5.0673 0)
					(end 5.0673 0)
				)
			)
			(stroke
				(width 0)
				(type default)
			)
			(fill no)
			(layer "F.CrtYd")
		)
		(fp_poly
			(pts
				(arc
					(start 5.0673 0)
					(mid -5.0673 0)
					(end 5.0673 0)
				)
			)
			(stroke
				(width 0)
				(type default)
			)
			(fill no)
			(layer "B.Fab")
		)
		(fp_poly
			(pts
				(arc
					(start 5.0673 0)
					(mid -5.0673 0)
					(end 5.0673 0)
				)
			)
			(stroke
				(width 0)
				(type default)
			)
			(fill no)
			(layer "F.Fab")
		)
		(pad "1" thru_hole circle
			(at 0 0)
			(size 9.525 9.525)
			(drill 3.5052)
			(layers "*.Cu" "*.Mask")
			(remove_unused_layers no)
			(net "Net_41")
			(clearance -2.5019)
			(thermal_gap 0.3048)
			(padstack
				(mode front_inner_back)
				(layer "Inner"
					(shape circle)
					(size 3.9116 3.9116)
					(clearance 0.3048)
				)
				(layer "B.Cu"
					(shape circle)
					(size 9.525 9.525)
					(clearance -2.5019)
				)
			)
		)
	)
	(footprint ""
		(layer "F.Cu")
		(at 28.346146 -178.17211 -90)
		(property "Reference" "R492"
			(at 0 0 270)
			(layer "F.SilkS")
			(hide yes)
			(effects
				(font
					(size 1.27 1.27)
				)
			)
		)
		(property "Value" "475KR2F-GP"
			(at 0.064008 -3.993896 270)
			(unlocked yes)
			(layer "F.Fab")
			(hide yes)
			(effects
				(font
					(size 1.016 1.016)
					(thickness 0.1524)
				)
			)
		)
		(property "Device Type" "R402H16"
			(at 0.064008 -5.517896 270)
			(unlocked yes)
			(layer "F.Fab")
			(hide yes)
			(effects
				(font
					(size 1.016 1.016)
					(thickness 0.1524)
				)
			)
		)
		(duplicate_pad_numbers_are_jumpers no)
		(fp_line
			(start -0.508 -0.9398)
			(end -0.508 0.9398)
			(stroke
				(width 0.1524)
				(type default)
			)
			(layer "F.SilkS")
		)
		(fp_line
			(start 0.508 -0.9398)
			(end -0.508 -0.9398)
			(stroke
				(width 0.1524)
				(type default)
			)
			(layer "F.SilkS")
		)
		(fp_rect
			(start -0.508 0.9398)
			(end 0.508 -0.9398)
			(stroke
				(width 0)
				(type default)
			)
			(fill no)
			(layer "F.CrtYd")
		)
		(fp_rect
			(start -0.508 0.9398)
			(end 0.508 -0.9398)
			(stroke
				(width 0)
				(type default)
			)
			(fill no)
			(layer "F.Fab")
		)
		(pad "1" smd custom
			(at 0 -0.4445 270)
			(size 0.1397 0.1397)
			(layers "F.Cu" "F.Mask" "F.Paste")
			(net "P3V3_STBY_MODE")
			(options
				(clearance outline)
				(anchor circle)
			)
			(primitives
				(gr_poly
					(pts
						(arc
							(start -0.1778 -0.2794)
							(mid -0.249642 -0.249642)
							(end -0.2794 -0.1778)
						)
						(arc
							(start -0.2794 0.1778)
							(mid -0.249642 0.249642)
							(end -0.1778 0.2794)
						)
						(arc
							(start 0.1778 0.2794)
							(mid 0.249642 0.249642)
							(end 0.2794 0.1778)
						)
						(arc
							(start 0.2794 -0.1778)
							(mid 0.249642 -0.249642)
							(end 0.1778 -0.2794)
						)
					)
					(width 0)
					(fill yes)
				)
			)
		)
		(pad "2" smd custom
			(at 0 0.4445 270)
			(size 0.1397 0.1397)
			(layers "F.Cu" "F.Mask" "F.Paste")
			(net "PWRGD_P3V3_STBY")
			(options
				(clearance outline)
				(anchor circle)
			)
			(primitives
				(gr_poly
					(pts
						(arc
							(start -0.1778 -0.2794)
							(mid -0.249642 -0.249642)
							(end -0.2794 -0.1778)
						)
						(arc
							(start -0.2794 0.1778)
							(mid -0.249642 0.249642)
							(end -0.1778 0.2794)
						)
						(arc
							(start 0.1778 0.2794)
							(mid 0.249642 0.249642)
							(end 0.2794 0.1778)
						)
						(arc
							(start 0.2794 -0.1778)
							(mid 0.249642 -0.249642)
							(end 0.1778 -0.2794)
						)
					)
					(width 0)
					(fill yes)
				)
			)
		)
	)
	(footprint ""
		(layer "F.Cu")
		(at 188.214 -139.1158)
		(property "Reference" "TP213"
			(at 0 0 0)
			(layer "F.SilkS")
			(hide yes)
			(effects
				(font
					(size 1.27 1.27)
				)
			)
		)
		(property "Value" "TPAD28-2-GP"
			(at -0.0127 -1.6637 0)
			(unlocked yes)
			(layer "F.Fab")
			(hide yes)
			(effects
				(font
					(size 1.016 1.016)
					(thickness 0.1524)
				)
			)
		)
		(property "Device Type" "TPAD28"
			(at -0.0127 -3.1877 0)
			(unlocked yes)
			(layer "F.Fab")
			(hide yes)
			(effects
				(font
					(size 1.016 1.016)
					(thickness 0.1524)
				)
			)
		)
		(duplicate_pad_numbers_are_jumpers no)
		(fp_poly
			(pts
				(arc
					(start 0.3556 0)
					(mid -0.3556 0)
					(end 0.3556 0)
				)
			)
			(stroke
				(width 0)
				(type default)
			)
			(fill no)
			(layer "F.CrtYd")
		)
		(fp_poly
			(pts
				(arc
					(start 0.6096 0)
					(mid -0.6096 0)
					(end 0.6096 0)
				)
			)
			(stroke
				(width 0)
				(type default)
			)
			(fill no)
			(layer "F.Fab")
		)
		(pad "1" smd circle
			(at 0 0)
			(size 0.7112 0.7112)
			(layers "F.Cu" "F.Mask" "F.Paste")
			(net "TP_M2_2_MFG_CLK")
		)
	)
	(footprint ""
		(layer "F.Cu")
		(at 213.77275 -45.587158)
		(property "Reference" "R474"
			(at 0 0 0)
			(layer "F.SilkS")
			(hide yes)
			(effects
				(font
					(size 1.27 1.27)
				)
			)
		)
		(property "Value" "73K2R2F-GP"
			(at 0.064008 -3.993896 0)
			(unlocked yes)
			(layer "F.Fab")
			(hide yes)
			(effects
				(font
					(size 1.016 1.016)
					(thickness 0.1524)
				)
			)
		)
		(property "Device Type" "R402H16"
			(at 0.064008 -5.517896 0)
			(unlocked yes)
			(layer "F.Fab")
			(hide yes)
			(effects
				(font
					(size 1.016 1.016)
					(thickness 0.1524)
				)
			)
		)
		(duplicate_pad_numbers_are_jumpers no)
		(fp_line
			(start -0.508 -0.9398)
			(end -0.508 0.9398)
			(stroke
				(width 0.1524)
				(type default)
			)
			(layer "F.SilkS")
		)
		(fp_line
			(start 0.508 -0.9398)
			(end -0.508 -0.9398)
			(stroke
				(width 0.1524)
				(type default)
			)
			(layer "F.SilkS")
		)
		(fp_rect
			(start -0.508 0.9398)
			(end 0.508 -0.9398)
			(stroke
				(width 0)
				(type default)
			)
			(fill no)
			(layer "F.CrtYd")
		)
		(fp_rect
			(start -0.508 0.9398)
			(end 0.508 -0.9398)
			(stroke
				(width 0)
				(type default)
			)
			(fill no)
			(layer "F.Fab")
		)
		(pad "1" smd custom
			(at 0 -0.4445)
			(size 0.1397 0.1397)
			(layers "F.Cu" "F.Mask" "F.Paste")
			(net "P5V_VFB")
			(options
				(clearance outline)
				(anchor circle)
			)
			(primitives
				(gr_poly
					(pts
						(arc
							(start -0.1778 -0.2794)
							(mid -0.249642 -0.249642)
							(end -0.2794 -0.1778)
						)
						(arc
							(start -0.2794 0.1778)
							(mid -0.249642 0.249642)
							(end -0.1778 0.2794)
						)
						(arc
							(start 0.1778 0.2794)
							(mid 0.249642 0.249642)
							(end 0.2794 0.1778)
						)
						(arc
							(start 0.2794 -0.1778)
							(mid 0.249642 -0.249642)
							(end 0.1778 -0.2794)
						)
					)
					(width 0)
					(fill yes)
				)
			)
		)
		(pad "2" smd custom
			(at 0 0.4445)
			(size 0.1397 0.1397)
			(layers "F.Cu" "F.Mask" "F.Paste")
			(net "P5V_VFB_R")
			(options
				(clearance outline)
				(anchor circle)
			)
			(primitives
				(gr_poly
					(pts
						(arc
							(start -0.1778 -0.2794)
							(mid -0.249642 -0.249642)
							(end -0.2794 -0.1778)
						)
						(arc
							(start -0.2794 0.1778)
							(mid -0.249642 0.249642)
							(end -0.1778 0.2794)
						)
						(arc
							(start 0.1778 0.2794)
							(mid 0.249642 0.249642)
							(end 0.2794 0.1778)
						)
						(arc
							(start 0.2794 -0.1778)
							(mid 0.249642 -0.249642)
							(end 0.1778 -0.2794)
						)
					)
					(width 0)
					(fill yes)
				)
			)
		)
	)
	(footprint ""
		(layer "F.Cu")
		(at 83.358228 -75.749658 90)
		(property "Reference" "VIA10"
			(at 0 0 90)
			(layer "F.SilkS")
			(hide yes)
			(effects
				(font
					(size 1.27 1.27)
				)
			)
		)
		(property "Value" "85OHM-8L-1D6MM-L16L18-GP"
			(at 4.064 0.6096 90)
			(unlocked yes)
			(layer "F.Fab")
			(hide yes)
			(effects
				(font
					(size 1.016 1.016)
					(thickness 0.1524)
				)
			)
		)
		(property "Device Type" "VIA-PCIE-4P-368076"
			(at 4.064 -0.9144 90)
			(unlocked yes)
			(layer "F.Fab")
			(hide yes)
			(effects
				(font
					(size 1.016 1.016)
					(thickness 0.1524)
				)
			)
		)
		(duplicate_pad_numbers_are_jumpers no)
		(fp_rect
			(start -1.8415 0.381)
			(end 1.8415 -0.381)
			(stroke
				(width 0)
				(type default)
			)
			(fill no)
			(layer "F.CrtYd")
		)
		(fp_rect
			(start -1.8415 0.381)
			(end 1.8415 -0.381)
			(stroke
				(width 0)
				(type default)
			)
			(fill no)
			(layer "F.Fab")
		)
		(pad "1" thru_hole circle
			(at -1.4605 0 90)
			(size 0.508 0.508)
			(drill 0.254)
			(layers "*.Cu" "*.Mask")
			(remove_unused_layers no)
			(net "GND")
			(clearance 0.127)
			(thermal_gap 0.127)
		)
		(pad "2" thru_hole circle
			(at -0.4445 0 90)
			(size 0.508 0.508)
			(drill 0.254)
			(layers "*.Cu" "*.Mask")
			(remove_unused_layers no)
			(net "PCIE_IOM_TO_COMP_17_DP")
			(clearance 0.127)
			(thermal_gap 0.127)
		)
		(pad "3" thru_hole circle
			(at 0.4445 0 90)
			(size 0.508 0.508)
			(drill 0.254)
			(layers "*.Cu" "*.Mask")
			(remove_unused_layers no)
			(net "PCIE_IOM_TO_COMP_17_DN")
			(clearance 0.127)
			(thermal_gap 0.127)
		)
		(pad "4" thru_hole circle
			(at 1.4605 0 90)
			(size 0.508 0.508)
			(drill 0.254)
			(layers "*.Cu" "*.Mask")
			(remove_unused_layers no)
			(net "GND")
			(clearance 0.127)
			(thermal_gap 0.127)
		)
	)
	(footprint ""
		(layer "F.Cu")
		(at 186.817 -109.474 -90)
		(property "Reference" "R547"
			(at 0 0 270)
			(layer "F.SilkS")
			(hide yes)
			(effects
				(font
					(size 1.27 1.27)
				)
			)
		)
		(property "Value" "4K7R2F-GP"
			(at 0.064008 -3.993896 270)
			(unlocked yes)
			(layer "F.Fab")
			(hide yes)
			(effects
				(font
					(size 1.016 1.016)
					(thickness 0.1524)
				)
			)
		)
		(property "Device Type" "R402H16"
			(at 0.064008 -5.517896 270)
			(unlocked yes)
			(layer "F.Fab")
			(hide yes)
			(effects
				(font
					(size 1.016 1.016)
					(thickness 0.1524)
				)
			)
		)
		(duplicate_pad_numbers_are_jumpers no)
		(fp_line
			(start -0.508 -0.9398)
			(end -0.508 0.9398)
			(stroke
				(width 0.1524)
				(type default)
			)
			(layer "F.SilkS")
		)
		(fp_line
			(start 0.508 -0.9398)
			(end -0.508 -0.9398)
			(stroke
				(width 0.1524)
				(type default)
			)
			(layer "F.SilkS")
		)
		(fp_rect
			(start -0.508 0.9398)
			(end 0.508 -0.9398)
			(stroke
				(width 0)
				(type default)
			)
			(fill no)
			(layer "F.CrtYd")
		)
		(fp_rect
			(start -0.508 0.9398)
			(end 0.508 -0.9398)
			(stroke
				(width 0)
				(type default)
			)
			(fill no)
			(layer "F.Fab")
		)
		(pad "1" smd custom
			(at 0 -0.4445 270)
			(size 0.1397 0.1397)
			(layers "F.Cu" "F.Mask" "F.Paste")
			(net "P3V3_STBY")
			(options
				(clearance outline)
				(anchor circle)
			)
			(primitives
				(gr_poly
					(pts
						(arc
							(start -0.1778 -0.2794)
							(mid -0.249642 -0.249642)
							(end -0.2794 -0.1778)
						)
						(arc
							(start -0.2794 0.1778)
							(mid -0.249642 0.249642)
							(end -0.1778 0.2794)
						)
						(arc
							(start 0.1778 0.2794)
							(mid 0.249642 0.249642)
							(end 0.2794 0.1778)
						)
						(arc
							(start 0.2794 -0.1778)
							(mid 0.249642 -0.249642)
							(end 0.1778 -0.2794)
						)
					)
					(width 0)
					(fill yes)
				)
			)
		)
		(pad "2" smd custom
			(at 0 0.4445 270)
			(size 0.1397 0.1397)
			(layers "F.Cu" "F.Mask" "F.Paste")
			(net "TEMP_1_A2")
			(options
				(clearance outline)
				(anchor circle)
			)
			(primitives
				(gr_poly
					(pts
						(arc
							(start -0.1778 -0.2794)
							(mid -0.249642 -0.249642)
							(end -0.2794 -0.1778)
						)
						(arc
							(start -0.2794 0.1778)
							(mid -0.249642 0.249642)
							(end -0.1778 0.2794)
						)
						(arc
							(start 0.1778 0.2794)
							(mid 0.249642 0.249642)
							(end 0.2794 0.1778)
						)
						(arc
							(start 0.2794 -0.1778)
							(mid 0.249642 -0.249642)
							(end 0.1778 -0.2794)
						)
					)
					(width 0)
					(fill yes)
				)
			)
		)
	)
	(footprint ""
		(layer "F.Cu")
		(at 85.472016 -142.124176 -90)
		(property "Reference" "R329"
			(at 0 0 270)
			(layer "F.SilkS")
			(hide yes)
			(effects
				(font
					(size 1.27 1.27)
				)
			)
		)
		(property "Value" "0R2J-2-GP"
			(at 0.064008 -3.993896 270)
			(unlocked yes)
			(layer "F.Fab")
			(hide yes)
			(effects
				(font
					(size 1.016 1.016)
					(thickness 0.1524)
				)
			)
		)
		(property "Device Type" "R402H16"
			(at 0.064008 -5.517896 270)
			(unlocked yes)
			(layer "F.Fab")
			(hide yes)
			(effects
				(font
					(size 1.016 1.016)
					(thickness 0.1524)
				)
			)
		)
		(duplicate_pad_numbers_are_jumpers no)
		(fp_line
			(start -0.508 -0.9398)
			(end -0.508 0.9398)
			(stroke
				(width 0.1524)
				(type default)
			)
			(layer "F.SilkS")
		)
		(fp_line
			(start 0.508 -0.9398)
			(end -0.508 -0.9398)
			(stroke
				(width 0.1524)
				(type default)
			)
			(layer "F.SilkS")
		)
		(fp_rect
			(start -0.508 0.9398)
			(end 0.508 -0.9398)
			(stroke
				(width 0)
				(type default)
			)
			(fill no)
			(layer "F.CrtYd")
		)
		(fp_rect
			(start -0.508 0.9398)
			(end 0.508 -0.9398)
			(stroke
				(width 0)
				(type default)
			)
			(fill no)
			(layer "F.Fab")
		)
		(pad "1" smd custom
			(at 0 -0.4445 270)
			(size 0.1397 0.1397)
			(layers "F.Cu" "F.Mask" "F.Paste")
			(net "I2C_DPB_SCL")
			(options
				(clearance outline)
				(anchor circle)
			)
			(primitives
				(gr_poly
					(pts
						(arc
							(start -0.1778 -0.2794)
							(mid -0.249642 -0.249642)
							(end -0.2794 -0.1778)
						)
						(arc
							(start -0.2794 0.1778)
							(mid -0.249642 0.249642)
							(end -0.1778 0.2794)
						)
						(arc
							(start 0.1778 0.2794)
							(mid 0.249642 0.249642)
							(end 0.2794 0.1778)
						)
						(arc
							(start 0.2794 -0.1778)
							(mid 0.249642 -0.249642)
							(end 0.1778 -0.2794)
						)
					)
					(width 0)
					(fill yes)
				)
			)
		)
		(pad "2" smd custom
			(at 0 0.4445 270)
			(size 0.1397 0.1397)
			(layers "F.Cu" "F.Mask" "F.Paste")
			(net "I2C_DPB_SCL_R")
			(options
				(clearance outline)
				(anchor circle)
			)
			(primitives
				(gr_poly
					(pts
						(arc
							(start -0.1778 -0.2794)
							(mid -0.249642 -0.249642)
							(end -0.2794 -0.1778)
						)
						(arc
							(start -0.2794 0.1778)
							(mid -0.249642 0.249642)
							(end -0.1778 0.2794)
						)
						(arc
							(start 0.1778 0.2794)
							(mid 0.249642 0.249642)
							(end 0.2794 0.1778)
						)
						(arc
							(start 0.2794 -0.1778)
							(mid 0.249642 -0.249642)
							(end 0.1778 -0.2794)
						)
					)
					(width 0)
					(fill yes)
				)
			)
		)
	)
	(footprint ""
		(layer "F.Cu")
		(at 23.2537 -167.221916 180)
		(property "Reference" "C224"
			(at 0 0 180)
			(layer "F.SilkS")
			(hide yes)
			(effects
				(font
					(size 1.27 1.27)
				)
			)
		)
		(property "Value" "SC10U6D3V5KX-4GP"
			(at -0.0762 -6.1214 180)
			(unlocked yes)
			(layer "F.Fab")
			(hide yes)
			(effects
				(font
					(size 1.016 1.016)
					(thickness 0.1524)
				)
			)
		)
		(property "Device Type" "C805H58"
			(at -0.0762 -8.1534 180)
			(unlocked yes)
			(layer "F.Fab")
			(hide yes)
			(effects
				(font
					(size 1.016 1.016)
					(thickness 0.1524)
				)
			)
		)
		(duplicate_pad_numbers_are_jumpers no)
		(fp_line
			(start 0.635 0)
			(end -0.635 0)
			(stroke
				(width 0.508)
				(type default)
			)
			(layer "F.SilkS")
		)
		(fp_rect
			(start -0.9652 1.778)
			(end 0.9652 -1.778)
			(stroke
				(width 0)
				(type default)
			)
			(fill no)
			(layer "F.CrtYd")
		)
		(fp_poly
			(pts
				(xy -0.9652 -1.778) (xy 0.9652 -1.778) (xy 0.9652 1.778) (xy -0.9652 1.778)
			)
			(stroke
				(width 0)
				(type default)
			)
			(fill no)
			(layer "F.Fab")
		)
		(pad "1" smd rect
			(at 0 -0.9652 180)
			(size 1.397 1.143)
			(layers "F.Cu" "F.Mask" "F.Paste")
			(net "TPS74801_P1V2_STBY_OUT")
		)
		(pad "2" smd rect
			(at 0 0.9652 180)
			(size 1.397 1.143)
			(layers "F.Cu" "F.Mask" "F.Paste")
			(net "GND")
		)
	)
)
